(kicad_pcb
	(version 20241229)
	(generator "pcbnew")
	(generator_version "9.0")
	(general
		(thickness 1.711)
		(legacy_teardrops no)
	)
	(paper "A4")
	(title_block
		(title "Antmicro Baseboard for Jetson AGX Thor")
		(date "2026-02-18")
		(rev "1.1.0")
		(company "Antmicro Ltd")
		(comment 1 "www.antmicro.com")
		(comment 9 "footprints 733-734 of 1170")
	)
	(layers
		(0 "F.Cu" signal)
		(4 "In1.Cu" signal)
		(6 "In2.Cu" signal)
		(8 "In3.Cu" signal)
		(10 "In4.Cu" jumper)
		(12 "In5.Cu" signal)
		(14 "In6.Cu" signal)
		(16 "In7.Cu" signal)
		(18 "In8.Cu" signal)
		(2 "B.Cu" signal)
		(9 "F.Adhes" user "F.Adhesive")
		(11 "B.Adhes" user "B.Adhesive")
		(13 "F.Paste" user)
		(15 "B.Paste" user)
		(5 "F.SilkS" user "F.Silkscreen")
		(7 "B.SilkS" user "B.Silkscreen")
		(1 "F.Mask" user)
		(3 "B.Mask" user)
		(17 "Dwgs.User" user "User.Drawings")
		(19 "Cmts.User" user "User.Comments")
		(21 "Eco1.User" user "User.Eco1")
		(23 "Eco2.User" user "User.Eco2")
		(25 "Edge.Cuts" user)
		(27 "Margin" user)
		(31 "F.CrtYd" user "F.Courtyard")
		(29 "B.CrtYd" user "B.Courtyard")
		(35 "F.Fab" user)
		(33 "B.Fab" user)
	)
	(footprint "antmicro-footprints:Conn_FFC_WE_68715014x22"
		(locked yes)
		(layer "B.Cu")
		(at 62.44 103.71 90)
		(property "Reference" "J11"
			(at -15.49 2.56 0)
			(layer "B.SilkS")
			(effects
				(font
					(size 0.7 0.7)
					(thickness 0.15)
				)
				(justify right top mirror)
			)
		)
		(property "Value" "Conn_FFC_WE_68715014522"
			(at 0 -4.5 90)
			(layer "B.Fab")
			(effects
				(font
					(size 0.7 0.7)
					(thickness 0.15)
				)
				(justify right top mirror)
			)
		)
		(property "Datasheet" "https://www.we-online.com/components/products/datasheet/68715014522.pdf"
			(at 0 0 90)
			(layer "B.Fab")
			(hide yes)
			(effects
				(font
					(size 1.27 1.27)
					(thickness 0.15)
				)
				(justify mirror)
			)
		)
		(property "Description" "FFC connector"
			(at 0 0 90)
			(layer "B.Fab")
			(hide yes)
			(effects
				(font
					(size 1.27 1.27)
					(thickness 0.15)
				)
				(justify mirror)
			)
		)
		(property "MPN" "68715014522"
			(at 0 0 270)
			(unlocked yes)
			(layer "B.Fab")
			(hide yes)
			(effects
				(font
					(size 1 1)
					(thickness 0.15)
				)
				(justify mirror)
			)
		)
		(property "Manufacturer" "Würth Elektronik"
			(at 0 0 270)
			(unlocked yes)
			(layer "B.Fab")
			(hide yes)
			(effects
				(font
					(size 1 1)
					(thickness 0.15)
				)
				(justify mirror)
			)
		)
		(property "Author" "Antmicro"
			(at 0 0 270)
			(unlocked yes)
			(layer "B.Fab")
			(hide yes)
			(effects
				(font
					(size 1 1)
					(thickness 0.15)
				)
				(justify mirror)
			)
		)
		(property "License" "Apache-2.0"
			(at 0 0 270)
			(unlocked yes)
			(layer "B.Fab")
			(hide yes)
			(effects
				(font
					(size 1 1)
					(thickness 0.15)
				)
				(justify mirror)
			)
		)
		(sheetname "/CSI/")
		(sheetfile "csi.kicad_sch")
		(attr smd)
		(fp_line
			(start 15.85 -2.7)
			(end -15.85 -2.7)
			(stroke
				(width 0.15)
				(type solid)
			)
			(layer "B.SilkS")
		)
		(fp_line
			(start 15.85 -2.7)
			(end 15.85 2.15)
			(stroke
				(width 0.15)
				(type solid)
			)
			(layer "B.SilkS")
		)
		(fp_line
			(start -15.85 -2.7)
			(end -15.85 2.15)
			(stroke
				(width 0.15)
				(type solid)
			)
			(layer "B.SilkS")
		)
		(fp_line
			(start 15.85 2.15)
			(end 12.499 2.15)
			(stroke
				(width 0.15)
				(type solid)
			)
			(layer "B.SilkS")
		)
		(fp_line
			(start 12.499 2.15)
			(end 12.499 2.976)
			(stroke
				(width 0.15)
				(type solid)
			)
			(layer "B.SilkS")
		)
		(fp_line
			(start -12.5 2.15)
			(end -12.5 2.976)
			(stroke
				(width 0.15)
				(type solid)
			)
			(layer "B.SilkS")
		)
		(fp_line
			(start -15.85 2.15)
			(end -12.5 2.15)
			(stroke
				(width 0.15)
				(type solid)
			)
			(layer "B.SilkS")
		)
		(fp_line
			(start -12.5 2.976)
			(end 12.499 2.976)
			(stroke
				(width 0.15)
				(type solid)
			)
			(layer "B.SilkS")
		)
		(fp_circle
			(center -12.9 2.9)
			(end -12.85 2.85)
			(stroke
				(width 0.15)
				(type solid)
			)
			(fill yes)
			(layer "B.SilkS")
		)
		(fp_rect
			(start -16.2 3.25)
			(end 16.2 -3.55)
			(stroke
				(width 0.05)
				(type solid)
			)
			(fill no)
			(layer "B.CrtYd")
		)
		(fp_text user "Author: Antmicro"
			(at -16.2 -6.9 90)
			(layer "B.Fab")
			(effects
				(font
					(size 0.7 0.7)
					(thickness 0.15)
				)
				(justify right top mirror)
			)
		)
		(fp_text user "License: Apache-2.0"
			(at -16.2 -7.9 90)
			(layer "B.Fab")
			(effects
				(font
					(size 0.7 0.7)
					(thickness 0.15)
				)
				(justify right top mirror)
			)
		)
		(fp_text user "${REFERENCE}"
			(at -16.2 -5.9 90)
			(layer "B.Fab")
			(effects
				(font
					(size 0.7 0.7)
					(thickness 0.15)
				)
				(justify right top mirror)
			)
		)
		(pad "1" smd roundrect
			(at -12.25 2.15 90)
			(size 0.3 1.2)
			(layers "B.Cu" "B.Mask" "B.Paste")
			(roundrect_rratio 0.25)
			(net 154 "/CSI/CAM0.CSI3_D1-")
			(pintype "passive")
		)
		(pad "2" smd roundrect
			(at -11.75 2.15 90)
			(size 0.3 1.2)
			(layers "B.Cu" "B.Mask" "B.Paste")
			(roundrect_rratio 0.25)
			(net 161 "/CSI/CAM0.CSI3_D1+")
			(pintype "passive")
		)
		(pad "3" smd roundrect
			(at -11.25 2.15 90)
			(size 0.3 1.2)
			(layers "B.Cu" "B.Mask" "B.Paste")
			(roundrect_rratio 0.25)
			(net 63 "/CSI/CAM0.CSI3_D0-")
			(pintype "passive")
		)
		(pad "4" smd roundrect
			(at -10.75 2.15 90)
			(size 0.3 1.2)
			(layers "B.Cu" "B.Mask" "B.Paste")
			(roundrect_rratio 0.25)
			(net 52 "/CSI/CAM0.CSI3_D0+")
			(pintype "passive")
		)
		(pad "5" smd roundrect
			(at -10.25 2.15 90)
			(size 0.3 1.2)
			(layers "B.Cu" "B.Mask" "B.Paste")
			(roundrect_rratio 0.25)
			(net 170 "/CSI/CAM0.CSI2_D1-")
			(pintype "passive")
		)
		(pad "6" smd roundrect
			(at -9.75 2.15 90)
			(size 0.3 1.2)
			(layers "B.Cu" "B.Mask" "B.Paste")
			(roundrect_rratio 0.25)
			(net 89 "/CSI/CAM0.CSI2_D1+")
			(pintype "passive")
		)
		(pad "7" smd roundrect
			(at -9.25 2.15 90)
			(size 0.3 1.2)
			(layers "B.Cu" "B.Mask" "B.Paste")
			(roundrect_rratio 0.25)
			(net 64 "/CSI/CAM0.CSI2_D0-")
			(pintype "passive")
		)
		(pad "8" smd roundrect
			(at -8.75 2.15 90)
			(size 0.3 1.2)
			(layers "B.Cu" "B.Mask" "B.Paste")
			(roundrect_rratio 0.25)
			(net 88 "/CSI/CAM0.CSI2_D0+")
			(pintype "passive")
		)
		(pad "9" smd roundrect
			(at -8.25 2.15 90)
			(size 0.3 1.2)
			(layers "B.Cu" "B.Mask" "B.Paste")
			(roundrect_rratio 0.25)
			(net 1 "GND")
			(pintype "passive")
		)
		(pad "10" smd roundrect
			(at -7.75 2.15 90)
			(size 0.3 1.2)
			(layers "B.Cu" "B.Mask" "B.Paste")
			(roundrect_rratio 0.25)
			(net 68 "/CSI/CAM0.CSI2_CLK-")
			(pintype "passive")
		)
		(pad "11" smd roundrect
			(at -7.25 2.15 90)
			(size 0.3 1.2)
			(layers "B.Cu" "B.Mask" "B.Paste")
			(roundrect_rratio 0.25)
			(net 249 "/CSI/CAM0.CSI2_CLK+")
			(pintype "passive")
		)
		(pad "12" smd roundrect
			(at -6.75 2.15 90)
			(size 0.3 1.2)
			(layers "B.Cu" "B.Mask" "B.Paste")
			(roundrect_rratio 0.25)
			(net 1 "GND")
			(pintype "passive")
		)
		(pad "13" smd roundrect
			(at -6.25 2.15 90)
			(size 0.3 1.2)
			(layers "B.Cu" "B.Mask" "B.Paste")
			(roundrect_rratio 0.25)
			(net 203 "unconnected-(J11-Pad13)")
			(pintype "passive+no_connect")
		)
		(pad "14" smd roundrect
			(at -5.75 2.15 90)
			(size 0.3 1.2)
			(layers "B.Cu" "B.Mask" "B.Paste")
			(roundrect_rratio 0.25)
			(net 199 "unconnected-(J11-Pad14)")
			(pintype "passive+no_connect")
		)
		(pad "15" smd roundrect
			(at -5.25 2.15 90)
			(size 0.3 1.2)
			(layers "B.Cu" "B.Mask" "B.Paste")
			(roundrect_rratio 0.25)
			(net 1 "GND")
			(pintype "passive")
		)
		(pad "16" smd roundrect
			(at -4.75 2.15 90)
			(size 0.3 1.2)
			(layers "B.Cu" "B.Mask" "B.Paste")
			(roundrect_rratio 0.25)
			(net 196 "unconnected-(J11-Pad16)")
			(pintype "passive+no_connect")
		)
		(pad "17" smd roundrect
			(at -4.25 2.15 90)
			(size 0.3 1.2)
			(layers "B.Cu" "B.Mask" "B.Paste")
			(roundrect_rratio 0.25)
			(net 208 "unconnected-(J11-Pad17)")
			(pintype "passive+no_connect")
		)
		(pad "18" smd roundrect
			(at -3.75 2.15 90)
			(size 0.3 1.2)
			(layers "B.Cu" "B.Mask" "B.Paste")
			(roundrect_rratio 0.25)
			(net 1 "GND")
			(pintype "passive")
		)
		(pad "19" smd roundrect
			(at -3.25 2.15 90)
			(size 0.3 1.2)
			(layers "B.Cu" "B.Mask" "B.Paste")
			(roundrect_rratio 0.25)
			(net 143 "/CSI/CAM1.CSI1_D1-")
			(pintype "passive")
		)
		(pad "20" smd roundrect
			(at -2.75 2.15 90)
			(size 0.3 1.2)
			(layers "B.Cu" "B.Mask" "B.Paste")
			(roundrect_rratio 0.25)
			(net 93 "/CSI/CAM1.CSI1_D1+")
			(pintype "passive")
		)
		(pad "21" smd roundrect
			(at -2.25 2.15 90)
			(size 0.3 1.2)
			(layers "B.Cu" "B.Mask" "B.Paste")
			(roundrect_rratio 0.25)
			(net 134 "/CSI/CAM1.CSI1_D0-")
			(pintype "passive")
		)
		(pad "22" smd roundrect
			(at -1.75 2.15 90)
			(size 0.3 1.2)
			(layers "B.Cu" "B.Mask" "B.Paste")
			(roundrect_rratio 0.25)
			(net 77 "/CSI/CAM1.CSI1_D0+")
			(pintype "passive")
		)
		(pad "23" smd roundrect
			(at -1.25 2.15 90)
			(size 0.3 1.2)
			(layers "B.Cu" "B.Mask" "B.Paste")
			(roundrect_rratio 0.25)
			(net 153 "/CSI/CAM1.CSI0_D1-")
			(pintype "passive")
		)
		(pad "24" smd roundrect
			(at -0.75 2.15 90)
			(size 0.3 1.2)
			(layers "B.Cu" "B.Mask" "B.Paste")
			(roundrect_rratio 0.25)
			(net 54 "/CSI/CAM1.CSI0_D1+")
			(pintype "passive")
		)
		(pad "25" smd roundrect
			(at -0.25 2.15 90)
			(size 0.3 1.2)
			(layers "B.Cu" "B.Mask" "B.Paste")
			(roundrect_rratio 0.25)
			(net 113 "/CSI/CAM1.CSI0_D0-")
			(pintype "passive")
		)
		(pad "26" smd roundrect
			(at 0.248 2.15 90)
			(size 0.3 1.2)
			(layers "B.Cu" "B.Mask" "B.Paste")
			(roundrect_rratio 0.25)
			(net 157 "/CSI/CAM1.CSI0_D0+")
			(pintype "passive")
		)
		(pad "27" smd roundrect
			(at 0.748 2.15 90)
			(size 0.3 1.2)
			(layers "B.Cu" "B.Mask" "B.Paste")
			(roundrect_rratio 0.25)
			(net 1 "GND")
			(pintype "passive")
		)
		(pad "28" smd roundrect
			(at 1.249 2.15 90)
			(size 0.3 1.2)
			(layers "B.Cu" "B.Mask" "B.Paste")
			(roundrect_rratio 0.25)
			(net 66 "/CSI/CAM1.CSI0_CLK-")
			(pintype "passive")
		)
		(pad "29" smd roundrect
			(at 1.749 2.15 90)
			(size 0.3 1.2)
			(layers "B.Cu" "B.Mask" "B.Paste")
			(roundrect_rratio 0.25)
			(net 136 "/CSI/CAM1.CSI0_CLK+")
			(pintype "passive")
		)
		(pad "30" smd roundrect
			(at 2.249 2.15 90)
			(size 0.3 1.2)
			(layers "B.Cu" "B.Mask" "B.Paste")
			(roundrect_rratio 0.25)
			(net 1 "GND")
			(pintype "passive")
		)
		(pad "31" smd roundrect
			(at 2.749 2.15 90)
			(size 0.3 1.2)
			(layers "B.Cu" "B.Mask" "B.Paste")
			(roundrect_rratio 0.25)
			(net 202 "unconnected-(J11-Pad31)")
			(pintype "passive+no_connect")
		)
		(pad "32" smd roundrect
			(at 3.249 2.15 90)
			(size 0.3 1.2)
			(layers "B.Cu" "B.Mask" "B.Paste")
			(roundrect_rratio 0.25)
			(net 186 "/CSI/VSYNC_CAM0_3V3")
			(pintype "passive")
		)
		(pad "33" smd roundrect
			(at 3.749 2.15 90)
			(size 0.3 1.2)
			(layers "B.Cu" "B.Mask" "B.Paste")
			(roundrect_rratio 0.25)
			(net 198 "unconnected-(J11-Pad33)")
			(pintype "passive+no_connect")
		)
		(pad "34" smd roundrect
			(at 4.248 2.15 90)
			(size 0.3 1.2)
			(layers "B.Cu" "B.Mask" "B.Paste")
			(roundrect_rratio 0.25)
			(net 194 "/CSI/VSYNC_CAM1_3V3")
			(pintype "passive")
		)
		(pad "35" smd roundrect
			(at 4.748 2.15 90)
			(size 0.3 1.2)
			(layers "B.Cu" "B.Mask" "B.Paste")
			(roundrect_rratio 0.25)
			(net 200 "unconnected-(J11-Pad35)")
			(pintype "passive+no_connect")
		)
		(pad "36" smd roundrect
			(at 5.248 2.15 90)
			(size 0.3 1.2)
			(layers "B.Cu" "B.Mask" "B.Paste")
			(roundrect_rratio 0.25)
			(net 209 "unconnected-(J11-Pad36)")
			(pintype "passive+no_connect")
		)
		(pad "37" smd roundrect
			(at 5.749 2.15 90)
			(size 0.3 1.2)
			(layers "B.Cu" "B.Mask" "B.Paste")
			(roundrect_rratio 0.25)
			(net 204 "unconnected-(J11-Pad37)")
			(pintype "passive+no_connect")
		)
		(pad "38" smd roundrect
			(at 6.249 2.15 90)
			(size 0.3 1.2)
			(layers "B.Cu" "B.Mask" "B.Paste")
			(roundrect_rratio 0.25)
			(net 197 "unconnected-(J11-Pad38)")
			(pintype "passive+no_connect")
		)
		(pad "39" smd roundrect
			(at 6.749 2.15 90)
			(size 0.3 1.2)
			(layers "B.Cu" "B.Mask" "B.Paste")
			(roundrect_rratio 0.25)
			(net 1374 "Net-(J11-Pad39)")
			(pintype "passive")
		)
		(pad "40" smd roundrect
			(at 7.249 2.15 90)
			(size 0.3 1.2)
			(layers "B.Cu" "B.Mask" "B.Paste")
			(roundrect_rratio 0.25)
			(net 1377 "Net-(J11-Pad40)")
			(pintype "passive")
		)
		(pad "41" smd roundrect
			(at 7.749 2.15 90)
			(size 0.3 1.2)
			(layers "B.Cu" "B.Mask" "B.Paste")
			(roundrect_rratio 0.25)
			(net 1376 "Net-(J11-Pad41)")
			(pintype "passive")
		)
		(pad "42" smd roundrect
			(at 8.249 2.15 90)
			(size 0.3 1.2)
			(layers "B.Cu" "B.Mask" "B.Paste")
			(roundrect_rratio 0.25)
			(net 1375 "Net-(J11-Pad42)")
			(pintype "passive")
		)
		(pad "43" smd roundrect
			(at 8.749 2.15 90)
			(size 0.3 1.2)
			(layers "B.Cu" "B.Mask" "B.Paste")
			(roundrect_rratio 0.25)
			(net 207 "unconnected-(J11-Pad43)")
			(pintype "passive+no_connect")
		)
		(pad "44" smd roundrect
			(at 9.249 2.15 90)
			(size 0.3 1.2)
			(layers "B.Cu" "B.Mask" "B.Paste")
			(roundrect_rratio 0.25)
			(net 205 "unconnected-(J11-Pad44)")
			(pintype "passive+no_connect")
		)
		(pad "45" smd roundrect
			(at 9.749 2.15 90)
			(size 0.3 1.2)
			(layers "B.Cu" "B.Mask" "B.Paste")
			(roundrect_rratio 0.25)
			(net 211 "unconnected-(J11-Pad45)")
			(pintype "passive+no_connect")
		)
		(pad "46" smd roundrect
			(at 10.249 2.15 90)
			(size 0.3 1.2)
			(layers "B.Cu" "B.Mask" "B.Paste")
			(roundrect_rratio 0.25)
			(net 206 "unconnected-(J11-Pad46)")
			(pintype "passive+no_connect")
		)
		(pad "47" smd roundrect
			(at 10.749 2.15 90)
			(size 0.3 1.2)
			(layers "B.Cu" "B.Mask" "B.Paste")
			(roundrect_rratio 0.25)
			(net 6 "/CSI/CSIA_3V3")
			(pintype "passive")
		)
		(pad "48" smd roundrect
			(at 11.249 2.15 90)
			(size 0.3 1.2)
			(layers "B.Cu" "B.Mask" "B.Paste")
			(roundrect_rratio 0.25)
			(net 6 "/CSI/CSIA_3V3")
			(pintype "passive")
		)
		(pad "49" smd roundrect
			(at 11.749 2.15 90)
			(size 0.3 1.2)
			(layers "B.Cu" "B.Mask" "B.Paste")
			(roundrect_rratio 0.25)
			(net 7 "/CSI/CSIA_5V")
			(pintype "passive")
		)
		(pad "50" smd roundrect
			(at 12.249 2.15 90)
			(size 0.3 1.2)
			(layers "B.Cu" "B.Mask" "B.Paste")
			(roundrect_rratio 0.25)
			(net 7 "/CSI/CSIA_5V")
			(pintype "passive")
		)
		(pad "MP1" smd roundrect
			(at -14.198 0.3 90)
			(size 2.7 3)
			(layers "B.Cu" "B.Mask" "B.Paste")
			(roundrect_rratio 0.05)
			(net 1 "GND")
			(pinfunction "MP")
			(pintype "passive")
		)
		(pad "MP2" smd roundrect
			(at 14.198 0.3 90)
			(size 2.7 3)
			(layers "B.Cu" "B.Mask" "B.Paste")
			(roundrect_rratio 0.05)
			(net 1 "GND")
			(pinfunction "MP")
			(pintype "passive")
		)
	)
	(footprint "antmicro-footprints:R_0402_1005Metric"
		(layer "B.Cu")
		(at 202.3 130.5 90)
		(descr "Resistor SMD 0402")
		(tags "resistor SMD 0402")
		(property "Reference" "R21"
			(at -3.1 -0.3 90)
			(layer "B.SilkS")
			(effects
				(font
					(size 0.7 0.7)
					(thickness 0.15)
				)
				(justify right top mirror)
			)
		)
		(property "Value" "R_0R_0402"
			(at -1.011843 -1.772047 90)
			(layer "B.Fab")
			(effects
				(font
					(size 0.7 0.7)
					(thickness 0.15)
				)
				(justify right top mirror)
			)
		)
		(property "Datasheet" "https://industrial.panasonic.com/cdbs/www-data/pdf/RDA0000/AOA0000C301.pdf"
			(at 0 0 90)
			(layer "B.Fab")
			(hide yes)
			(effects
				(font
					(size 1.27 1.27)
					(thickness 0.15)
				)
				(justify mirror)
			)
		)
		(property "Description" "SMD Chip Resistor, Jumper, 0 ohm, 100 mW, 0402 [1005 Metric], Thick Film, General Purpose"
			(at 0 0 90)
			(layer "B.Fab")
			(hide yes)
			(effects
				(font
					(size 1.27 1.27)
					(thickness 0.15)
				)
				(justify mirror)
			)
		)
		(property "Manufacturer" "Panasonic"
			(at 0 0 270)
			(unlocked yes)
			(layer "B.Fab")
			(hide yes)
			(effects
				(font
					(size 1 1)
					(thickness 0.15)
				)
				(justify mirror)
			)
		)
		(property "MPN" "ERJ2GE0R00X"
			(at 0 0 270)
			(unlocked yes)
			(layer "B.Fab")
			(hide yes)
			(effects
				(font
					(size 1 1)
					(thickness 0.15)
				)
				(justify mirror)
			)
		)
		(property "Val" "0R"
			(at 0 0 270)
			(unlocked yes)
			(layer "B.Fab")
			(hide yes)
			(effects
				(font
					(size 1 1)
					(thickness 0.15)
				)
				(justify mirror)
			)
		)
		(property "License" "Apache-2.0"
			(at 0 0 270)
			(unlocked yes)
			(layer "B.Fab")
			(hide yes)
			(effects
				(font
					(size 1 1)
					(thickness 0.15)
				)
				(justify mirror)
			)
		)
		(property "Author" "Antmicro"
			(at 0 0 270)
			(unlocked yes)
			(layer "B.Fab")
			(hide yes)
			(effects
				(font
					(size 1 1)
					(thickness 0.15)
				)
				(justify mirror)
			)
		)
		(property "Tolerance" "~"
			(at 0 0 270)
			(unlocked yes)
			(layer "B.Fab")
			(hide yes)
			(effects
				(font
					(size 1 1)
					(thickness 0.15)
				)
				(justify mirror)
			)
		)
		(property "Current" "1A"
			(at 0 0 270)
			(unlocked yes)
			(layer "B.Fab")
			(hide yes)
			(effects
				(font
					(size 1 1)
					(thickness 0.15)
				)
				(justify mirror)
			)
		)
		(sheetname "/USB Hub/")
		(sheetfile "usb_hub.kicad_sch")
		(attr smd)
		(fp_rect
			(start -0.925 0.47)
			(end 0.925 -0.47)
			(stroke
				(width 0.05)
				(type default)
			)
			(fill no)
			(layer "B.CrtYd")
		)
		(fp_rect
			(start -0.5 0.25)
			(end 0.5 -0.25)
			(stroke
				(width 0.15)
				(type solid)
			)
			(fill no)
			(layer "B.Fab")
		)
		(fp_text user "License: Apache-2.0"
			(at -0.95 -5.169 90)
			(layer "B.Fab")
			(effects
				(font
					(size 0.7 0.7)
					(thickness 0.15)
				)
				(justify right top mirror)
			)
		)
		(fp_text user "${REFERENCE}"
			(at -0.95 -3.168 90)
			(layer "B.Fab")
			(effects
				(font
					(size 0.7 0.7)
					(thickness 0.15)
				)
				(justify right top mirror)
			)
		)
		(fp_text user "Author: Antmicro"
			(at -0.95 -4.169 90)
			(layer "B.Fab")
			(effects
				(font
					(size 0.7 0.7)
					(thickness 0.15)
				)
				(justify right top mirror)
			)
		)
		(pad "1" smd roundrect
			(at -0.48 0 90)
			(size 0.59 0.64)
			(layers "B.Cu" "B.Mask" "B.Paste")
			(roundrect_rratio 0.25)
			(net 1111 "Net-(U21-USB2DN_DP3)")
			(pintype "passive")
		)
		(pad "2" smd roundrect
			(at 0.48 0 90)
			(size 0.59 0.64)
			(layers "B.Cu" "B.Mask" "B.Paste")
			(roundrect_rratio 0.25)
			(net 2 "+3V3")
			(pintype "passive")
		)
	)
)
